# T6G (Grand Teton) — schematic netlist excerpt (pin names and nets, part order shuffled) for the footprints in the layout excerpt that follows; sources: Cadence DE-HDL packaged netlist, KiCad conversion of 04192023_DAF0TMB3IC0_F0TG_MB_C_brd_V02_OCP.brd

R1683  Q_RES  10 1% CHIP  pkg 0402LF  page 94 : A = I3C_SPD_DDRGL_CPU0_SDA ; B = I3C_SPD_DDRI_CPU0_SDA
C244  Q_CAP  22UF 4V 20% X6S  pkg C0402  page 323 : A = P0V9_CPU1_RT_2D ; B = GND

(kicad_pcb
	(version 20260206)
	(generator "pcbnew")
	(generator_version "10.0")
	(general
		(thickness 1.6)
		(legacy_teardrops no)
	)
	(paper "A4")
	(title_block
		(title "04192023_DAF0TMB3IC0_F0TG_MB_C_brd_V02_OCP.brd")
		(comment 1 "Grand Teton / footprints 6616-6617 of 8354")
	)
	(layers
		(0 "F.Cu" signal "TOP")
		(4 "In1.Cu" signal "GND")
		(6 "In2.Cu" signal "IN1")
		(8 "In3.Cu" signal "GND1")
		(10 "In4.Cu" signal "IN2")
		(12 "In5.Cu" signal "GND2")
		(14 "In6.Cu" signal "IN3")
		(16 "In7.Cu" signal "GND3")
		(18 "In8.Cu" signal "VCC")
		(20 "In9.Cu" signal "VCC1")
		(22 "In10.Cu" signal "GND4")
		(24 "In11.Cu" signal "IN4")
		(26 "In12.Cu" signal "GND5")
		(28 "In13.Cu" signal "IN5")
		(30 "In14.Cu" signal "GND6")
		(32 "In15.Cu" signal "IN6")
		(34 "In16.Cu" signal "GND7")
		(2 "B.Cu" signal "BOTTOM")
		(9 "F.Adhes" user "F.Adhesive")
		(11 "B.Adhes" user "B.Adhesive")
		(13 "F.Paste" user "Package Geometry/Pastemask Top")
		(15 "B.Paste" user "Package Geometry/Pastemask Bottom")
		(5 "F.SilkS" user "Ref Des/Silkscreen Top")
		(7 "B.SilkS" user "Ref Des/Silkscreen Bottom")
		(1 "F.Mask" user "Board Geometry/Soldermask Top")
		(3 "B.Mask" user "Board Geometry/Soldermask Bottom")
		(17 "Dwgs.User" user "User.Drawings")
		(19 "Cmts.User" user "User.Comments")
		(21 "Eco1.User" user "User.Eco1")
		(23 "Eco2.User" user "User.Eco2")
		(25 "Edge.Cuts" user "Board Geometry/Outline")
		(27 "Margin" user)
		(31 "F.CrtYd" user "Package Geometry/Place Bound Top")
		(29 "B.CrtYd" user "Package Geometry/Place Bound Bottom")
		(35 "F.Fab" user "Ref Des/Assembly Top")
		(33 "B.Fab" user "Ref Des/Assembly Bottom")
	)
	(footprint ""
		(layer "B.Cu")
		(at 430.80051 -195.85051 180)
		(property "Reference" "R1683"
			(at 0 0 0)
			(layer "B.SilkS")
			(hide yes)
			(effects
				(font
					(size 1.27 1.27)
				)
				(justify mirror)
			)
		)
		(property "Value" ""
			(at 0 0 0)
			(layer "B.Fab")
			(effects
				(font
					(size 1.27 1.27)
				)
				(justify mirror)
			)
		)
		(duplicate_pad_numbers_are_jumpers no)
		(fp_line
			(start 0.7874 0.4064)
			(end 0.7874 -0.4064)
			(stroke
				(width 0.1524)
				(type default)
			)
			(layer "B.SilkS")
		)
		(fp_line
			(start 0.7874 -0.4064)
			(end -0.7874 -0.4064)
			(stroke
				(width 0.1524)
				(type default)
			)
			(layer "B.SilkS")
		)
		(fp_line
			(start -0.7874 0.4064)
			(end 0.7874 0.4064)
			(stroke
				(width 0.1524)
				(type default)
			)
			(layer "B.SilkS")
		)
		(fp_line
			(start -0.7874 -0.4064)
			(end -0.7874 0.4064)
			(stroke
				(width 0.1524)
				(type default)
			)
			(layer "B.SilkS")
		)
		(fp_line
			(start 0.67945 0.3048)
			(end 0.67945 -0.305054)
			(stroke
				(width 0.1)
				(type default)
			)
			(layer "B.Fab")
		)
		(fp_line
			(start 0.67945 -0.305054)
			(end 0.12065 -0.305054)
			(stroke
				(width 0.1)
				(type default)
			)
			(layer "B.Fab")
		)
		(fp_line
			(start 0.12065 0.3048)
			(end 0.67945 0.3048)
			(stroke
				(width 0.1)
				(type default)
			)
			(layer "B.Fab")
		)
		(fp_line
			(start 0.12065 0.2794)
			(end 0.12065 0.3048)
			(stroke
				(width 0.1)
				(type default)
			)
			(layer "B.Fab")
		)
		(fp_line
			(start 0.12065 -0.2794)
			(end -0.12065 -0.2794)
			(stroke
				(width 0.1)
				(type default)
			)
			(layer "B.Fab")
		)
		(fp_line
			(start 0.12065 -0.305054)
			(end 0.12065 -0.2794)
			(stroke
				(width 0.1)
				(type default)
			)
			(layer "B.Fab")
		)
		(fp_line
			(start -0.120396 0.3048)
			(end -0.120396 0.2794)
			(stroke
				(width 0.1)
				(type default)
			)
			(layer "B.Fab")
		)
		(fp_line
			(start -0.120396 0.2794)
			(end 0.12065 0.2794)
			(stroke
				(width 0.1)
				(type default)
			)
			(layer "B.Fab")
		)
		(fp_line
			(start -0.12065 -0.2794)
			(end -0.12065 -0.3048)
			(stroke
				(width 0.1)
				(type default)
			)
			(layer "B.Fab")
		)
		(fp_line
			(start -0.12065 -0.3048)
			(end -0.67945 -0.3048)
			(stroke
				(width 0.1)
				(type default)
			)
			(layer "B.Fab")
		)
		(fp_line
			(start -0.67945 0.3048)
			(end -0.120396 0.3048)
			(stroke
				(width 0.1)
				(type default)
			)
			(layer "B.Fab")
		)
		(fp_line
			(start -0.67945 -0.3048)
			(end -0.67945 0.3048)
			(stroke
				(width 0.1)
				(type default)
			)
			(layer "B.Fab")
		)
		(pad "1" smd circle
			(at 0.40005 0)
			(size 0 0)
			(layers "B.Cu" "B.Mask" "B.Paste")
			(net "I3C_SPD_DDRGL_CPU0_SDA")
		)
		(pad "2" smd circle
			(at -0.40005 0)
			(size 0 0)
			(layers "B.Cu" "B.Mask" "B.Paste")
			(net "I3C_SPD_DDRI_CPU0_SDA")
		)
	)
	(footprint ""
		(layer "B.Cu")
		(at 58.1914 -390.560052 90)
		(property "Reference" "C244"
			(at 0 0 90)
			(layer "B.SilkS")
			(hide yes)
			(effects
				(font
					(size 1.27 1.27)
				)
				(justify mirror)
			)
		)
		(property "Value" ""
			(at 0 0 90)
			(layer "B.Fab")
			(effects
				(font
					(size 1.27 1.27)
				)
				(justify mirror)
			)
		)
		(duplicate_pad_numbers_are_jumpers no)
		(fp_line
			(start 0.7874 -0.4064)
			(end -0.7874 -0.4064)
			(stroke
				(width 0.1524)
				(type default)
			)
			(layer "B.SilkS")
		)
		(fp_line
			(start -0.7874 -0.4064)
			(end -0.7874 0.4064)
			(stroke
				(width 0.1524)
				(type default)
			)
			(layer "B.SilkS")
		)
		(fp_line
			(start 0.7874 0.4064)
			(end 0.7874 -0.4064)
			(stroke
				(width 0.1524)
				(type default)
			)
			(layer "B.SilkS")
		)
		(fp_line
			(start -0.7874 0.4064)
			(end 0.7874 0.4064)
			(stroke
				(width 0.1524)
				(type default)
			)
			(layer "B.SilkS")
		)
		(fp_line
			(start 0.67945 -0.305054)
			(end 0.12065 -0.305054)
			(stroke
				(width 0.1)
				(type default)
			)
			(layer "B.Fab")
		)
		(fp_line
			(start 0.12065 -0.305054)
			(end 0.12065 -0.2794)
			(stroke
				(width 0.1)
				(type default)
			)
			(layer "B.Fab")
		)
		(fp_line
			(start -0.12065 -0.3048)
			(end -0.67945 -0.3048)
			(stroke
				(width 0.1)
				(type default)
			)
			(layer "B.Fab")
		)
		(fp_line
			(start -0.67945 -0.3048)
			(end -0.67945 0.3048)
			(stroke
				(width 0.1)
				(type default)
			)
			(layer "B.Fab")
		)
		(fp_line
			(start 0.12065 -0.2794)
			(end -0.12065 -0.2794)
			(stroke
				(width 0.1)
				(type default)
			)
			(layer "B.Fab")
		)
		(fp_line
			(start -0.12065 -0.2794)
			(end -0.12065 -0.3048)
			(stroke
				(width 0.1)
				(type default)
			)
			(layer "B.Fab")
		)
		(fp_line
			(start 0.12065 0.2794)
			(end 0.12065 0.3048)
			(stroke
				(width 0.1)
				(type default)
			)
			(layer "B.Fab")
		)
		(fp_line
			(start -0.120396 0.2794)
			(end 0.12065 0.2794)
			(stroke
				(width 0.1)
				(type default)
			)
			(layer "B.Fab")
		)
		(fp_line
			(start 0.67945 0.3048)
			(end 0.67945 -0.305054)
			(stroke
				(width 0.1)
				(type default)
			)
			(layer "B.Fab")
		)
		(fp_line
			(start 0.12065 0.3048)
			(end 0.67945 0.3048)
			(stroke
				(width 0.1)
				(type default)
			)
			(layer "B.Fab")
		)
		(fp_line
			(start -0.120396 0.3048)
			(end -0.120396 0.2794)
			(stroke
				(width 0.1)
				(type default)
			)
			(layer "B.Fab")
		)
		(fp_line
			(start -0.67945 0.3048)
			(end -0.120396 0.3048)
			(stroke
				(width 0.1)
				(type default)
			)
			(layer "B.Fab")
		)
		(pad "1" smd circle
			(at 0.40005 0 270)
			(size 0 0)
			(layers "B.Cu" "B.Mask" "B.Paste")
			(net "P0V9_CPU1_RT_2D")
		)
		(pad "2" smd circle
			(at -0.40005 0 270)
			(size 0 0)
			(layers "B.Cu" "B.Mask" "B.Paste")
			(net "GND")
		)
	)
)
